(kicad_pcb
	(version 20260206)
	(generator "pcbnew")
	(generator_version "10.0")
	(general
		(thickness 1.6)
		(legacy_teardrops no)
	)
	(paper "A4")
	(title_block
		(title "9054_F0T_PDB_BD_GPU_F_V04_1213_1550_OCP.brd")
		(comment 1 "Grand Teton / footprints 428-433 of 608")
	)
	(layers
		(0 "F.Cu" signal "TOP")
		(4 "In1.Cu" signal "GND")
		(6 "In2.Cu" signal "IN1")
		(8 "In3.Cu" signal "GND1")
		(10 "In4.Cu" signal "VCC")
		(12 "In5.Cu" signal "VCC1")
		(14 "In6.Cu" signal "GND2")
		(16 "In7.Cu" signal "IN2")
		(18 "In8.Cu" signal "GND3")
		(2 "B.Cu" signal "BOTTOM")
		(9 "F.Adhes" user "F.Adhesive")
		(11 "B.Adhes" user "B.Adhesive")
		(13 "F.Paste" user "Package Geometry/Pastemask Top")
		(15 "B.Paste" user "Package Geometry/Pastemask Bottom")
		(5 "F.SilkS" user "Ref Des/Silkscreen Top")
		(7 "B.SilkS" user "Ref Des/Silkscreen Bottom")
		(1 "F.Mask" user "Board Geometry/Soldermask Top")
		(3 "B.Mask" user "Board Geometry/Soldermask Bottom")
		(17 "Dwgs.User" user "User.Drawings")
		(19 "Cmts.User" user "User.Comments")
		(21 "Eco1.User" user "User.Eco1")
		(23 "Eco2.User" user "User.Eco2")
		(25 "Edge.Cuts" user "Board Geometry/Outline")
		(27 "Margin" user)
		(31 "F.CrtYd" user "Package Geometry/Place Bound Top")
		(29 "B.CrtYd" user "Package Geometry/Place Bound Bottom")
		(35 "F.Fab" user "Ref Des/Assembly Top")
		(33 "B.Fab" user "Ref Des/Assembly Bottom")
	)
	(footprint ""
		(layer "B.Cu")
		(at 267.9954 -77.978 -90)
		(property "Reference" "PC587"
			(at 0 0 90)
			(layer "B.SilkS")
			(hide yes)
			(effects
				(font
					(size 1.27 1.27)
				)
				(justify mirror)
			)
		)
		(property "Value" ""
			(at 0 0 90)
			(layer "B.Fab")
			(effects
				(font
					(size 1.27 1.27)
				)
				(justify mirror)
			)
		)
		(duplicate_pad_numbers_are_jumpers no)
		(fp_line
			(start -2.2098 0.9398)
			(end 2.2098 0.9398)
			(stroke
				(width 0.1524)
				(type default)
			)
			(layer "B.SilkS")
		)
		(fp_line
			(start 2.2098 0.9398)
			(end 2.2098 -0.9398)
			(stroke
				(width 0.1524)
				(type default)
			)
			(layer "B.SilkS")
		)
		(fp_line
			(start -2.2098 -0.9398)
			(end -2.2098 0.9398)
			(stroke
				(width 0.1524)
				(type default)
			)
			(layer "B.SilkS")
		)
		(fp_line
			(start 2.2098 -0.9398)
			(end -2.2098 -0.9398)
			(stroke
				(width 0.1524)
				(type default)
			)
			(layer "B.SilkS")
		)
		(fp_line
			(start -1.6764 0.9398)
			(end -1.6764 -0.9398)
			(stroke
				(width 0.1)
				(type default)
			)
			(layer "B.Fab")
		)
		(fp_line
			(start 1.6764 0.9398)
			(end -1.6764 0.9398)
			(stroke
				(width 0.1)
				(type default)
			)
			(layer "B.Fab")
		)
		(fp_line
			(start -1.6764 -0.9398)
			(end 1.6764 -0.9398)
			(stroke
				(width 0.1)
				(type default)
			)
			(layer "B.Fab")
		)
		(fp_line
			(start 1.6764 -0.9398)
			(end 1.6764 0.9398)
			(stroke
				(width 0.1)
				(type default)
			)
			(layer "B.Fab")
		)
		(pad "1" smd rect
			(at 1.4732 0 270)
			(size 1.1684 1.5748)
			(layers "B.Cu" "B.Mask" "B.Paste")
			(net "P52V_HS1_VCC")
		)
		(pad "2" smd rect
			(at -1.4732 0 270)
			(size 1.1684 1.5748)
			(layers "B.Cu" "B.Mask" "B.Paste")
			(net "GND_FIELD_SIGNAL")
		)
	)
	(footprint ""
		(layer "B.Cu")
		(at 169.1894 -76.327)
		(property "Reference" "PR7034"
			(at 0 0 0)
			(layer "B.SilkS")
			(hide yes)
			(effects
				(font
					(size 1.27 1.27)
				)
				(justify mirror)
			)
		)
		(property "Value" ""
			(at 0 0 0)
			(layer "B.Fab")
			(effects
				(font
					(size 1.27 1.27)
				)
				(justify mirror)
			)
		)
		(duplicate_pad_numbers_are_jumpers no)
		(fp_line
			(start -0.7874 -0.4064)
			(end -0.7874 0.4064)
			(stroke
				(width 0.1524)
				(type default)
			)
			(layer "B.SilkS")
		)
		(fp_line
			(start -0.7874 0.4064)
			(end 0.7874 0.4064)
			(stroke
				(width 0.1524)
				(type default)
			)
			(layer "B.SilkS")
		)
		(fp_line
			(start 0.7874 -0.4064)
			(end -0.7874 -0.4064)
			(stroke
				(width 0.1524)
				(type default)
			)
			(layer "B.SilkS")
		)
		(fp_line
			(start 0.7874 0.4064)
			(end 0.7874 -0.4064)
			(stroke
				(width 0.1524)
				(type default)
			)
			(layer "B.SilkS")
		)
		(fp_line
			(start -0.67945 -0.3048)
			(end -0.67945 0.3048)
			(stroke
				(width 0.1)
				(type default)
			)
			(layer "B.Fab")
		)
		(fp_line
			(start -0.67945 0.3048)
			(end -0.120396 0.3048)
			(stroke
				(width 0.1)
				(type default)
			)
			(layer "B.Fab")
		)
		(fp_line
			(start -0.12065 -0.3048)
			(end -0.67945 -0.3048)
			(stroke
				(width 0.1)
				(type default)
			)
			(layer "B.Fab")
		)
		(fp_line
			(start -0.12065 -0.2794)
			(end -0.12065 -0.3048)
			(stroke
				(width 0.1)
				(type default)
			)
			(layer "B.Fab")
		)
		(fp_line
			(start -0.120396 0.2794)
			(end 0.12065 0.2794)
			(stroke
				(width 0.1)
				(type default)
			)
			(layer "B.Fab")
		)
		(fp_line
			(start -0.120396 0.3048)
			(end -0.120396 0.2794)
			(stroke
				(width 0.1)
				(type default)
			)
			(layer "B.Fab")
		)
		(fp_line
			(start 0.12065 -0.305054)
			(end 0.12065 -0.2794)
			(stroke
				(width 0.1)
				(type default)
			)
			(layer "B.Fab")
		)
		(fp_line
			(start 0.12065 -0.2794)
			(end -0.12065 -0.2794)
			(stroke
				(width 0.1)
				(type default)
			)
			(layer "B.Fab")
		)
		(fp_line
			(start 0.12065 0.2794)
			(end 0.12065 0.3048)
			(stroke
				(width 0.1)
				(type default)
			)
			(layer "B.Fab")
		)
		(fp_line
			(start 0.12065 0.3048)
			(end 0.67945 0.3048)
			(stroke
				(width 0.1)
				(type default)
			)
			(layer "B.Fab")
		)
		(fp_line
			(start 0.67945 -0.305054)
			(end 0.12065 -0.305054)
			(stroke
				(width 0.1)
				(type default)
			)
			(layer "B.Fab")
		)
		(fp_line
			(start 0.67945 0.3048)
			(end 0.67945 -0.305054)
			(stroke
				(width 0.1)
				(type default)
			)
			(layer "B.Fab")
		)
		(pad "1" smd circle
			(at 0.40005 0 180)
			(size 0 0)
			(layers "B.Cu" "B.Mask" "B.Paste")
			(net "P52V_HS2_MCB")
		)
		(pad "2" smd circle
			(at -0.40005 0 180)
			(size 0 0)
			(layers "B.Cu" "B.Mask" "B.Paste")
			(net "GND1_FIELD_SIGNAL")
		)
	)
	(footprint ""
		(layer "B.Cu")
		(at 104.013 -43.053)
		(property "Reference" "PC598"
			(at 0 0 0)
			(layer "B.SilkS")
			(hide yes)
			(effects
				(font
					(size 1.27 1.27)
				)
				(justify mirror)
			)
		)
		(property "Value" ""
			(at 0 0 0)
			(layer "B.Fab")
			(effects
				(font
					(size 1.27 1.27)
				)
				(justify mirror)
			)
		)
		(duplicate_pad_numbers_are_jumpers no)
		(fp_line
			(start -1.2954 -0.5842)
			(end -1.2954 0.5842)
			(stroke
				(width 0.1524)
				(type default)
			)
			(layer "B.SilkS")
		)
		(fp_line
			(start -1.2954 0.5842)
			(end 1.2954 0.5842)
			(stroke
				(width 0.1524)
				(type default)
			)
			(layer "B.SilkS")
		)
		(fp_line
			(start 1.2954 -0.5842)
			(end -1.2954 -0.5842)
			(stroke
				(width 0.1524)
				(type default)
			)
			(layer "B.SilkS")
		)
		(fp_line
			(start 1.2954 0.5842)
			(end 1.2954 -0.5842)
			(stroke
				(width 0.1524)
				(type default)
			)
			(layer "B.SilkS")
		)
		(fp_line
			(start -1.1938 -0.4064)
			(end -1.1938 0.4064)
			(stroke
				(width 0.1)
				(type default)
			)
			(layer "B.Fab")
		)
		(fp_line
			(start -1.1938 0.4064)
			(end -0.8636 0.4064)
			(stroke
				(width 0.1)
				(type default)
			)
			(layer "B.Fab")
		)
		(fp_line
			(start -0.8636 -0.4572)
			(end -0.8636 -0.4064)
			(stroke
				(width 0.1)
				(type default)
			)
			(layer "B.Fab")
		)
		(fp_line
			(start -0.8636 -0.4064)
			(end -1.1938 -0.4064)
			(stroke
				(width 0.1)
				(type default)
			)
			(layer "B.Fab")
		)
		(fp_line
			(start -0.8636 0.4064)
			(end -0.8636 0.4572)
			(stroke
				(width 0.1)
				(type default)
			)
			(layer "B.Fab")
		)
		(fp_line
			(start -0.8636 0.4572)
			(end 0.8636 0.4572)
			(stroke
				(width 0.1)
				(type default)
			)
			(layer "B.Fab")
		)
		(fp_line
			(start 0.8636 -0.4572)
			(end -0.8636 -0.4572)
			(stroke
				(width 0.1)
				(type default)
			)
			(layer "B.Fab")
		)
		(fp_line
			(start 0.8636 -0.4064)
			(end 0.8636 -0.4572)
			(stroke
				(width 0.1)
				(type default)
			)
			(layer "B.Fab")
		)
		(fp_line
			(start 0.8636 0.4064)
			(end 1.1938 0.4064)
			(stroke
				(width 0.1)
				(type default)
			)
			(layer "B.Fab")
		)
		(fp_line
			(start 0.8636 0.4572)
			(end 0.8636 0.4064)
			(stroke
				(width 0.1)
				(type default)
			)
			(layer "B.Fab")
		)
		(fp_line
			(start 1.1938 -0.4064)
			(end 0.8636 -0.4064)
			(stroke
				(width 0.1)
				(type default)
			)
			(layer "B.Fab")
		)
		(fp_line
			(start 1.1938 0.4064)
			(end 1.1938 -0.4064)
			(stroke
				(width 0.1)
				(type default)
			)
			(layer "B.Fab")
		)
		(pad "1" smd rect
			(at 0.7366 0 270)
			(size 0.7112 0.8128)
			(layers "B.Cu" "B.Mask" "B.Paste")
			(net "P52V_HS2_4287_GATE2_RC")
		)
		(pad "2" smd rect
			(at -0.7366 0 270)
			(size 0.7112 0.8128)
			(layers "B.Cu" "B.Mask" "B.Paste")
			(net "P52V_HS2")
		)
	)
	(footprint ""
		(layer "B.Cu")
		(at 279.2984 -72.39 180)
		(property "Reference" "PR20"
			(at 0 0 0)
			(layer "B.SilkS")
			(hide yes)
			(effects
				(font
					(size 1.27 1.27)
				)
				(justify mirror)
			)
		)
		(property "Value" ""
			(at 0 0 0)
			(layer "B.Fab")
			(effects
				(font
					(size 1.27 1.27)
				)
				(justify mirror)
			)
		)
		(duplicate_pad_numbers_are_jumpers no)
		(fp_line
			(start 0.7874 0.4064)
			(end 0.7874 -0.4064)
			(stroke
				(width 0.1524)
				(type default)
			)
			(layer "B.SilkS")
		)
		(fp_line
			(start 0.7874 -0.4064)
			(end -0.7874 -0.4064)
			(stroke
				(width 0.1524)
				(type default)
			)
			(layer "B.SilkS")
		)
		(fp_line
			(start -0.7874 0.4064)
			(end 0.7874 0.4064)
			(stroke
				(width 0.1524)
				(type default)
			)
			(layer "B.SilkS")
		)
		(fp_line
			(start -0.7874 -0.4064)
			(end -0.7874 0.4064)
			(stroke
				(width 0.1524)
				(type default)
			)
			(layer "B.SilkS")
		)
		(fp_line
			(start 0.67945 0.3048)
			(end 0.67945 -0.305054)
			(stroke
				(width 0.1)
				(type default)
			)
			(layer "B.Fab")
		)
		(fp_line
			(start 0.67945 -0.305054)
			(end 0.12065 -0.305054)
			(stroke
				(width 0.1)
				(type default)
			)
			(layer "B.Fab")
		)
		(fp_line
			(start 0.12065 0.3048)
			(end 0.67945 0.3048)
			(stroke
				(width 0.1)
				(type default)
			)
			(layer "B.Fab")
		)
		(fp_line
			(start 0.12065 0.2794)
			(end 0.12065 0.3048)
			(stroke
				(width 0.1)
				(type default)
			)
			(layer "B.Fab")
		)
		(fp_line
			(start 0.12065 -0.2794)
			(end -0.12065 -0.2794)
			(stroke
				(width 0.1)
				(type default)
			)
			(layer "B.Fab")
		)
		(fp_line
			(start 0.12065 -0.305054)
			(end 0.12065 -0.2794)
			(stroke
				(width 0.1)
				(type default)
			)
			(layer "B.Fab")
		)
		(fp_line
			(start -0.120396 0.3048)
			(end -0.120396 0.2794)
			(stroke
				(width 0.1)
				(type default)
			)
			(layer "B.Fab")
		)
		(fp_line
			(start -0.120396 0.2794)
			(end 0.12065 0.2794)
			(stroke
				(width 0.1)
				(type default)
			)
			(layer "B.Fab")
		)
		(fp_line
			(start -0.12065 -0.2794)
			(end -0.12065 -0.3048)
			(stroke
				(width 0.1)
				(type default)
			)
			(layer "B.Fab")
		)
		(fp_line
			(start -0.12065 -0.3048)
			(end -0.67945 -0.3048)
			(stroke
				(width 0.1)
				(type default)
			)
			(layer "B.Fab")
		)
		(fp_line
			(start -0.67945 0.3048)
			(end -0.120396 0.3048)
			(stroke
				(width 0.1)
				(type default)
			)
			(layer "B.Fab")
		)
		(fp_line
			(start -0.67945 -0.3048)
			(end -0.67945 0.3048)
			(stroke
				(width 0.1)
				(type default)
			)
			(layer "B.Fab")
		)
		(pad "1" smd circle
			(at 0.40005 0)
			(size 0 0)
			(layers "B.Cu" "B.Mask" "B.Paste")
			(net "P52V_HS1_ISTART")
		)
		(pad "2" smd circle
			(at -0.40005 0)
			(size 0 0)
			(layers "B.Cu" "B.Mask" "B.Paste")
			(net "GND_FIELD_SIGNAL")
		)
	)
	(footprint ""
		(layer "B.Cu")
		(at 290.9824 -60.833 90)
		(property "Reference" "R159"
			(at 0 0 90)
			(layer "B.SilkS")
			(hide yes)
			(effects
				(font
					(size 1.27 1.27)
				)
				(justify mirror)
			)
		)
		(property "Value" ""
			(at 0 0 90)
			(layer "B.Fab")
			(effects
				(font
					(size 1.27 1.27)
				)
				(justify mirror)
			)
		)
		(duplicate_pad_numbers_are_jumpers no)
		(fp_line
			(start 0.7874 -0.4064)
			(end -0.7874 -0.4064)
			(stroke
				(width 0.1524)
				(type default)
			)
			(layer "B.SilkS")
		)
		(fp_line
			(start -0.7874 -0.4064)
			(end -0.7874 0.4064)
			(stroke
				(width 0.1524)
				(type default)
			)
			(layer "B.SilkS")
		)
		(fp_line
			(start 0.7874 0.4064)
			(end 0.7874 -0.4064)
			(stroke
				(width 0.1524)
				(type default)
			)
			(layer "B.SilkS")
		)
		(fp_line
			(start -0.7874 0.4064)
			(end 0.7874 0.4064)
			(stroke
				(width 0.1524)
				(type default)
			)
			(layer "B.SilkS")
		)
		(fp_line
			(start 0.67945 -0.305054)
			(end 0.12065 -0.305054)
			(stroke
				(width 0.1)
				(type default)
			)
			(layer "B.Fab")
		)
		(fp_line
			(start 0.12065 -0.305054)
			(end 0.12065 -0.2794)
			(stroke
				(width 0.1)
				(type default)
			)
			(layer "B.Fab")
		)
		(fp_line
			(start -0.12065 -0.3048)
			(end -0.67945 -0.3048)
			(stroke
				(width 0.1)
				(type default)
			)
			(layer "B.Fab")
		)
		(fp_line
			(start -0.67945 -0.3048)
			(end -0.67945 0.3048)
			(stroke
				(width 0.1)
				(type default)
			)
			(layer "B.Fab")
		)
		(fp_line
			(start 0.12065 -0.2794)
			(end -0.12065 -0.2794)
			(stroke
				(width 0.1)
				(type default)
			)
			(layer "B.Fab")
		)
		(fp_line
			(start -0.12065 -0.2794)
			(end -0.12065 -0.3048)
			(stroke
				(width 0.1)
				(type default)
			)
			(layer "B.Fab")
		)
		(fp_line
			(start 0.12065 0.2794)
			(end 0.12065 0.3048)
			(stroke
				(width 0.1)
				(type default)
			)
			(layer "B.Fab")
		)
		(fp_line
			(start -0.120396 0.2794)
			(end 0.12065 0.2794)
			(stroke
				(width 0.1)
				(type default)
			)
			(layer "B.Fab")
		)
		(fp_line
			(start 0.67945 0.3048)
			(end 0.67945 -0.305054)
			(stroke
				(width 0.1)
				(type default)
			)
			(layer "B.Fab")
		)
		(fp_line
			(start 0.12065 0.3048)
			(end 0.67945 0.3048)
			(stroke
				(width 0.1)
				(type default)
			)
			(layer "B.Fab")
		)
		(fp_line
			(start -0.120396 0.3048)
			(end -0.120396 0.2794)
			(stroke
				(width 0.1)
				(type default)
			)
			(layer "B.Fab")
		)
		(fp_line
			(start -0.67945 0.3048)
			(end -0.120396 0.3048)
			(stroke
				(width 0.1)
				(type default)
			)
			(layer "B.Fab")
		)
		(pad "1" smd circle
			(at 0.40005 0 270)
			(size 0 0)
			(layers "B.Cu" "B.Mask" "B.Paste")
			(net "P52V_HS1_ADR1")
		)
		(pad "2" smd circle
			(at -0.40005 0 270)
			(size 0 0)
			(layers "B.Cu" "B.Mask" "B.Paste")
			(net "GND_FIELD_SIGNAL")
		)
	)
	(footprint ""
		(layer "B.Cu")
		(at 155.621736 -77.216 90)
		(property "Reference" "R5873"
			(at 0 0 90)
			(layer "B.SilkS")
			(hide yes)
			(effects
				(font
					(size 1.27 1.27)
				)
				(justify mirror)
			)
		)
		(property "Value" ""
			(at 0 0 90)
			(layer "B.Fab")
			(effects
				(font
					(size 1.27 1.27)
				)
				(justify mirror)
			)
		)
		(duplicate_pad_numbers_are_jumpers no)
		(fp_line
			(start 0.7874 -0.4064)
			(end -0.7874 -0.4064)
			(stroke
				(width 0.1524)
				(type default)
			)
			(layer "B.SilkS")
		)
		(fp_line
			(start -0.7874 -0.4064)
			(end -0.7874 0.4064)
			(stroke
				(width 0.1524)
				(type default)
			)
			(layer "B.SilkS")
		)
		(fp_line
			(start 0.7874 0.4064)
			(end 0.7874 -0.4064)
			(stroke
				(width 0.1524)
				(type default)
			)
			(layer "B.SilkS")
		)
		(fp_line
			(start -0.7874 0.4064)
			(end 0.7874 0.4064)
			(stroke
				(width 0.1524)
				(type default)
			)
			(layer "B.SilkS")
		)
		(fp_line
			(start 0.67945 -0.305054)
			(end 0.12065 -0.305054)
			(stroke
				(width 0.1)
				(type default)
			)
			(layer "B.Fab")
		)
		(fp_line
			(start 0.12065 -0.305054)
			(end 0.12065 -0.2794)
			(stroke
				(width 0.1)
				(type default)
			)
			(layer "B.Fab")
		)
		(fp_line
			(start -0.12065 -0.3048)
			(end -0.67945 -0.3048)
			(stroke
				(width 0.1)
				(type default)
			)
			(layer "B.Fab")
		)
		(fp_line
			(start -0.67945 -0.3048)
			(end -0.67945 0.3048)
			(stroke
				(width 0.1)
				(type default)
			)
			(layer "B.Fab")
		)
		(fp_line
			(start 0.12065 -0.2794)
			(end -0.12065 -0.2794)
			(stroke
				(width 0.1)
				(type default)
			)
			(layer "B.Fab")
		)
		(fp_line
			(start -0.12065 -0.2794)
			(end -0.12065 -0.3048)
			(stroke
				(width 0.1)
				(type default)
			)
			(layer "B.Fab")
		)
		(fp_line
			(start 0.12065 0.2794)
			(end 0.12065 0.3048)
			(stroke
				(width 0.1)
				(type default)
			)
			(layer "B.Fab")
		)
		(fp_line
			(start -0.120396 0.2794)
			(end 0.12065 0.2794)
			(stroke
				(width 0.1)
				(type default)
			)
			(layer "B.Fab")
		)
		(fp_line
			(start 0.67945 0.3048)
			(end 0.67945 -0.305054)
			(stroke
				(width 0.1)
				(type default)
			)
			(layer "B.Fab")
		)
		(fp_line
			(start 0.12065 0.3048)
			(end 0.67945 0.3048)
			(stroke
				(width 0.1)
				(type default)
			)
			(layer "B.Fab")
		)
		(fp_line
			(start -0.120396 0.3048)
			(end -0.120396 0.2794)
			(stroke
				(width 0.1)
				(type default)
			)
			(layer "B.Fab")
		)
		(fp_line
			(start -0.67945 0.3048)
			(end -0.120396 0.3048)
			(stroke
				(width 0.1)
				(type default)
			)
			(layer "B.Fab")
		)
		(pad "1" smd circle
			(at 0.40005 0 270)
			(size 0 0)
			(layers "B.Cu" "B.Mask" "B.Paste")
			(net "P52V_HS2_INTVCC")
		)
		(pad "2" smd circle
			(at -0.40005 0 270)
			(size 0 0)
			(layers "B.Cu" "B.Mask" "B.Paste")
			(net "P52V_HS2_ADR0")
		)
	)
)
